(kicad_pcb
	(version 20260206)
	(generator "pcbnew")
	(generator_version "10.0")
	(general
		(thickness 1.6)
		(legacy_teardrops no)
	)
	(paper "A4")
	(title_block
		(title "01162023_DA0F0TEBIF0_F0T_Expander_BD_F_brd_V02_OCP.brd")
		(comment 1 "Grand Teton / footprints 9053-9063 of 9728")
	)
	(layers
		(0 "F.Cu" signal "TOP")
		(4 "In1.Cu" signal "GND")
		(6 "In2.Cu" signal "VCC")
		(8 "In3.Cu" signal "VCC1")
		(10 "In4.Cu" signal "GND1")
		(12 "In5.Cu" signal "IN1")
		(14 "In6.Cu" signal "GND2")
		(16 "In7.Cu" signal "IN2")
		(18 "In8.Cu" signal "GND3")
		(20 "In9.Cu" signal "IN3")
		(22 "In10.Cu" signal "GND4")
		(24 "In11.Cu" signal "IN4")
		(26 "In12.Cu" signal "GND5")
		(28 "In13.Cu" signal "IN5")
		(30 "In14.Cu" signal "GND6")
		(32 "In15.Cu" signal "IN6")
		(34 "In16.Cu" signal "GND7")
		(2 "B.Cu" signal "BOTTOM")
		(9 "F.Adhes" user "F.Adhesive")
		(11 "B.Adhes" user "B.Adhesive")
		(13 "F.Paste" user "Package Geometry/Pastemask Top")
		(15 "B.Paste" user "Package Geometry/Pastemask Bottom")
		(5 "F.SilkS" user "Ref Des/Silkscreen Top")
		(7 "B.SilkS" user "Ref Des/Silkscreen Bottom")
		(1 "F.Mask" user "Board Geometry/Soldermask Top")
		(3 "B.Mask" user "Board Geometry/Soldermask Bottom")
		(17 "Dwgs.User" user "User.Drawings")
		(19 "Cmts.User" user "User.Comments")
		(21 "Eco1.User" user "User.Eco1")
		(23 "Eco2.User" user "User.Eco2")
		(25 "Edge.Cuts" user "Board Geometry/Outline")
		(27 "Margin" user)
		(31 "F.CrtYd" user "Package Geometry/Place Bound Top")
		(29 "B.CrtYd" user "Package Geometry/Place Bound Bottom")
		(35 "F.Fab" user "Ref Des/Assembly Top")
		(33 "B.Fab" user "Ref Des/Assembly Bottom")
	)
	(footprint ""
		(layer "B.Cu")
		(at 415.549842 -299.699934 -90)
		(property "Reference" "C1961"
			(at 0 0 90)
			(layer "B.SilkS")
			(hide yes)
			(effects
				(font
					(size 1.27 1.27)
				)
				(justify mirror)
			)
		)
		(property "Value" ""
			(at 0 0 90)
			(layer "B.Fab")
			(effects
				(font
					(size 1.27 1.27)
				)
				(justify mirror)
			)
		)
		(duplicate_pad_numbers_are_jumpers no)
		(fp_line
			(start -0.299974 0.150114)
			(end 0.299974 0.150114)
			(stroke
				(width 0.1)
				(type default)
			)
			(layer "B.Fab")
		)
		(fp_line
			(start 0.299974 0.150114)
			(end 0.299974 -0.150114)
			(stroke
				(width 0.1)
				(type default)
			)
			(layer "B.Fab")
		)
		(fp_line
			(start -0.299974 -0.150114)
			(end -0.299974 0.150114)
			(stroke
				(width 0.1)
				(type default)
			)
			(layer "B.Fab")
		)
		(fp_line
			(start 0.299974 -0.150114)
			(end -0.299974 -0.150114)
			(stroke
				(width 0.1)
				(type default)
			)
			(layer "B.Fab")
		)
		(pad "1" smd rect
			(at 0.2667 0 90)
			(size 0.3048 0.381)
			(layers "B.Cu" "B.Mask" "B.Paste")
			(net "P0V8_SERDES_VDDA_PEX3")
		)
		(pad "2" smd rect
			(at -0.2667 0 90)
			(size 0.3048 0.381)
			(layers "B.Cu" "B.Mask" "B.Paste")
			(net "GND")
		)
	)
	(footprint ""
		(layer "B.Cu")
		(at 165.655244 -150.9776)
		(property "Reference" "R122"
			(at 0 0 0)
			(layer "B.SilkS")
			(hide yes)
			(effects
				(font
					(size 1.27 1.27)
				)
				(justify mirror)
			)
		)
		(property "Value" ""
			(at 0 0 0)
			(layer "B.Fab")
			(effects
				(font
					(size 1.27 1.27)
				)
				(justify mirror)
			)
		)
		(duplicate_pad_numbers_are_jumpers no)
		(fp_line
			(start -0.7874 -0.4064)
			(end -0.7874 0.4064)
			(stroke
				(width 0.1524)
				(type default)
			)
			(layer "B.SilkS")
		)
		(fp_line
			(start -0.7874 0.4064)
			(end 0.7874 0.4064)
			(stroke
				(width 0.1524)
				(type default)
			)
			(layer "B.SilkS")
		)
		(fp_line
			(start 0.7874 -0.4064)
			(end -0.7874 -0.4064)
			(stroke
				(width 0.1524)
				(type default)
			)
			(layer "B.SilkS")
		)
		(fp_line
			(start 0.7874 0.4064)
			(end 0.7874 -0.4064)
			(stroke
				(width 0.1524)
				(type default)
			)
			(layer "B.SilkS")
		)
		(fp_line
			(start -0.67945 -0.3048)
			(end -0.67945 0.3048)
			(stroke
				(width 0.1)
				(type default)
			)
			(layer "B.Fab")
		)
		(fp_line
			(start -0.67945 0.3048)
			(end -0.120396 0.3048)
			(stroke
				(width 0.1)
				(type default)
			)
			(layer "B.Fab")
		)
		(fp_line
			(start -0.12065 -0.3048)
			(end -0.67945 -0.3048)
			(stroke
				(width 0.1)
				(type default)
			)
			(layer "B.Fab")
		)
		(fp_line
			(start -0.12065 -0.2794)
			(end -0.12065 -0.3048)
			(stroke
				(width 0.1)
				(type default)
			)
			(layer "B.Fab")
		)
		(fp_line
			(start -0.120396 0.2794)
			(end 0.12065 0.2794)
			(stroke
				(width 0.1)
				(type default)
			)
			(layer "B.Fab")
		)
		(fp_line
			(start -0.120396 0.3048)
			(end -0.120396 0.2794)
			(stroke
				(width 0.1)
				(type default)
			)
			(layer "B.Fab")
		)
		(fp_line
			(start 0.12065 -0.305054)
			(end 0.12065 -0.2794)
			(stroke
				(width 0.1)
				(type default)
			)
			(layer "B.Fab")
		)
		(fp_line
			(start 0.12065 -0.2794)
			(end -0.12065 -0.2794)
			(stroke
				(width 0.1)
				(type default)
			)
			(layer "B.Fab")
		)
		(fp_line
			(start 0.12065 0.2794)
			(end 0.12065 0.3048)
			(stroke
				(width 0.1)
				(type default)
			)
			(layer "B.Fab")
		)
		(fp_line
			(start 0.12065 0.3048)
			(end 0.67945 0.3048)
			(stroke
				(width 0.1)
				(type default)
			)
			(layer "B.Fab")
		)
		(fp_line
			(start 0.67945 -0.305054)
			(end 0.12065 -0.305054)
			(stroke
				(width 0.1)
				(type default)
			)
			(layer "B.Fab")
		)
		(fp_line
			(start 0.67945 0.3048)
			(end 0.67945 -0.305054)
			(stroke
				(width 0.1)
				(type default)
			)
			(layer "B.Fab")
		)
		(pad "1" smd circle
			(at 0.40005 0 180)
			(size 0 0)
			(layers "B.Cu" "B.Mask" "B.Paste")
			(net "CLK_50M_NIC2_RBT_REF")
		)
		(pad "2" smd circle
			(at -0.40005 0 180)
			(size 0 0)
			(layers "B.Cu" "B.Mask" "B.Paste")
			(net "GND")
		)
	)
	(footprint ""
		(layer "B.Cu")
		(at 229.067614 -221.904052 90)
		(property "Reference" "C2017"
			(at 0 0 90)
			(layer "B.SilkS")
			(hide yes)
			(effects
				(font
					(size 1.27 1.27)
				)
				(justify mirror)
			)
		)
		(property "Value" ""
			(at 0 0 90)
			(layer "B.Fab")
			(effects
				(font
					(size 1.27 1.27)
				)
				(justify mirror)
			)
		)
		(duplicate_pad_numbers_are_jumpers no)
		(fp_line
			(start 0.69215 -0.2921)
			(end -0.69215 -0.2921)
			(stroke
				(width 0.1524)
				(type default)
			)
			(layer "B.SilkS")
		)
		(fp_line
			(start -0.69215 -0.2921)
			(end -0.69215 0.2921)
			(stroke
				(width 0.1524)
				(type default)
			)
			(layer "B.SilkS")
		)
		(fp_line
			(start 0.69215 0.2921)
			(end 0.69215 -0.2921)
			(stroke
				(width 0.1524)
				(type default)
			)
			(layer "B.SilkS")
		)
		(fp_line
			(start -0.69215 0.2921)
			(end 0.69215 0.2921)
			(stroke
				(width 0.1524)
				(type default)
			)
			(layer "B.SilkS")
		)
		(fp_line
			(start 0.51435 -0.2794)
			(end -0.51435 -0.2794)
			(stroke
				(width 0.1)
				(type default)
			)
			(layer "B.Fab")
		)
		(fp_line
			(start -0.51435 -0.2794)
			(end -0.51435 0.2794)
			(stroke
				(width 0.1)
				(type default)
			)
			(layer "B.Fab")
		)
		(fp_line
			(start 0.51435 0.2794)
			(end 0.51435 -0.2794)
			(stroke
				(width 0.1)
				(type default)
			)
			(layer "B.Fab")
		)
		(fp_line
			(start -0.51435 0.2794)
			(end 0.51435 0.2794)
			(stroke
				(width 0.1)
				(type default)
			)
			(layer "B.Fab")
		)
		(pad "1" smd circle
			(at 0.40005 0 270)
			(size 0 0)
			(layers "B.Cu" "B.Mask" "B.Paste")
			(net "P1V2_AUX")
		)
		(pad "2" smd circle
			(at -0.40005 0 270)
			(size 0 0)
			(layers "B.Cu" "B.Mask" "B.Paste")
			(net "GND")
		)
		(zone
			(layer "B.Cu")
			(hatch none 0.5)
			(connect_pads
				(clearance 0)
			)
			(min_thickness 0.25)
			(keepout
				(tracks not_allowed)
				(vias allowed)
				(pads allowed)
				(copperpour not_allowed)
				(footprints allowed)
			)
			(placement
				(enabled no)
				(sheetname "")
			)
			(fill
				(thermal_gap 0.5)
				(thermal_bridge_width 0.5)
				(island_removal_mode 0)
			)
			(polygon
				(pts
					(xy 229.155244 -222.094552) (xy 229.21341 -222.003112) (xy 229.21341 -221.803722) (xy 229.155244 -221.713552)
					(xy 228.979984 -221.713552) (xy 228.921564 -221.803722) (xy 228.921564 -222.003112) (xy 228.97973 -222.094552)
				)
			)
		)
	)
	(footprint ""
		(layer "B.Cu")
		(at 283.299916 -301.599854 -90)
		(property "Reference" "C1702"
			(at 0 0 90)
			(layer "B.SilkS")
			(hide yes)
			(effects
				(font
					(size 1.27 1.27)
				)
				(justify mirror)
			)
		)
		(property "Value" ""
			(at 0 0 90)
			(layer "B.Fab")
			(effects
				(font
					(size 1.27 1.27)
				)
				(justify mirror)
			)
		)
		(duplicate_pad_numbers_are_jumpers no)
		(fp_line
			(start -0.299974 0.150114)
			(end 0.299974 0.150114)
			(stroke
				(width 0.1)
				(type default)
			)
			(layer "B.Fab")
		)
		(fp_line
			(start 0.299974 0.150114)
			(end 0.299974 -0.150114)
			(stroke
				(width 0.1)
				(type default)
			)
			(layer "B.Fab")
		)
		(fp_line
			(start -0.299974 -0.150114)
			(end -0.299974 0.150114)
			(stroke
				(width 0.1)
				(type default)
			)
			(layer "B.Fab")
		)
		(fp_line
			(start 0.299974 -0.150114)
			(end -0.299974 -0.150114)
			(stroke
				(width 0.1)
				(type default)
			)
			(layer "B.Fab")
		)
		(pad "1" smd rect
			(at 0.2667 0 90)
			(size 0.3048 0.381)
			(layers "B.Cu" "B.Mask" "B.Paste")
			(net "P0V8_SERDES_VDDA_PEX2")
		)
		(pad "2" smd rect
			(at -0.2667 0 90)
			(size 0.3048 0.381)
			(layers "B.Cu" "B.Mask" "B.Paste")
			(net "GND")
		)
	)
	(footprint ""
		(layer "B.Cu")
		(at 63.449962 -292.099746 90)
		(property "Reference" "C1211"
			(at 0 0 90)
			(layer "B.SilkS")
			(hide yes)
			(effects
				(font
					(size 1.27 1.27)
				)
				(justify mirror)
			)
		)
		(property "Value" ""
			(at 0 0 90)
			(layer "B.Fab")
			(effects
				(font
					(size 1.27 1.27)
				)
				(justify mirror)
			)
		)
		(duplicate_pad_numbers_are_jumpers no)
		(fp_line
			(start 0.299974 -0.150114)
			(end -0.299974 -0.150114)
			(stroke
				(width 0.1)
				(type default)
			)
			(layer "B.Fab")
		)
		(fp_line
			(start -0.299974 -0.150114)
			(end -0.299974 0.150114)
			(stroke
				(width 0.1)
				(type default)
			)
			(layer "B.Fab")
		)
		(fp_line
			(start 0.299974 0.150114)
			(end 0.299974 -0.150114)
			(stroke
				(width 0.1)
				(type default)
			)
			(layer "B.Fab")
		)
		(fp_line
			(start -0.299974 0.150114)
			(end 0.299974 0.150114)
			(stroke
				(width 0.1)
				(type default)
			)
			(layer "B.Fab")
		)
		(pad "1" smd rect
			(at 0.2667 0 270)
			(size 0.3048 0.381)
			(layers "B.Cu" "B.Mask" "B.Paste")
			(net "P0V8_SERDES_VDDA_PEX0")
		)
		(pad "2" smd rect
			(at -0.2667 0 270)
			(size 0.3048 0.381)
			(layers "B.Cu" "B.Mask" "B.Paste")
			(net "GND")
		)
	)
	(footprint ""
		(layer "B.Cu")
		(at 401.299934 -288.299906 90)
		(property "Reference" "C3449"
			(at 0 0 90)
			(layer "B.SilkS")
			(hide yes)
			(effects
				(font
					(size 1.27 1.27)
				)
				(justify mirror)
			)
		)
		(property "Value" ""
			(at 0 0 90)
			(layer "B.Fab")
			(effects
				(font
					(size 1.27 1.27)
				)
				(justify mirror)
			)
		)
		(duplicate_pad_numbers_are_jumpers no)
		(fp_line
			(start 0.299974 -0.150114)
			(end -0.299974 -0.150114)
			(stroke
				(width 0.1)
				(type default)
			)
			(layer "B.Fab")
		)
		(fp_line
			(start -0.299974 -0.150114)
			(end -0.299974 0.150114)
			(stroke
				(width 0.1)
				(type default)
			)
			(layer "B.Fab")
		)
		(fp_line
			(start 0.299974 0.150114)
			(end 0.299974 -0.150114)
			(stroke
				(width 0.1)
				(type default)
			)
			(layer "B.Fab")
		)
		(fp_line
			(start -0.299974 0.150114)
			(end 0.299974 0.150114)
			(stroke
				(width 0.1)
				(type default)
			)
			(layer "B.Fab")
		)
		(pad "1" smd rect
			(at 0.2667 0 270)
			(size 0.3048 0.381)
			(layers "B.Cu" "B.Mask" "B.Paste")
			(net "P1V25_PEX3")
		)
		(pad "2" smd rect
			(at -0.2667 0 270)
			(size 0.3048 0.381)
			(layers "B.Cu" "B.Mask" "B.Paste")
			(net "GND")
		)
	)
	(footprint ""
		(layer "B.Cu")
		(at 73.400158 -111.791496)
		(property "Reference" "C862"
			(at 0 0 0)
			(layer "B.SilkS")
			(hide yes)
			(effects
				(font
					(size 1.27 1.27)
				)
				(justify mirror)
			)
		)
		(property "Value" ""
			(at 0 0 0)
			(layer "B.Fab")
			(effects
				(font
					(size 1.27 1.27)
				)
				(justify mirror)
			)
		)
		(duplicate_pad_numbers_are_jumpers no)
		(fp_line
			(start -0.299974 -0.150114)
			(end -0.299974 0.150114)
			(stroke
				(width 0.1)
				(type default)
			)
			(layer "B.Fab")
		)
		(fp_line
			(start -0.299974 0.150114)
			(end 0.299974 0.150114)
			(stroke
				(width 0.1)
				(type default)
			)
			(layer "B.Fab")
		)
		(fp_line
			(start 0.299974 -0.150114)
			(end -0.299974 -0.150114)
			(stroke
				(width 0.1)
				(type default)
			)
			(layer "B.Fab")
		)
		(fp_line
			(start 0.299974 0.150114)
			(end 0.299974 -0.150114)
			(stroke
				(width 0.1)
				(type default)
			)
			(layer "B.Fab")
		)
		(pad "1" smd rect
			(at 0.2667 0 180)
			(size 0.3048 0.381)
			(layers "B.Cu" "B.Mask" "B.Paste")
			(net "P12V_NIC1")
		)
		(pad "2" smd rect
			(at -0.2667 0 180)
			(size 0.3048 0.381)
			(layers "B.Cu" "B.Mask" "B.Paste")
			(net "GND")
		)
	)
	(footprint ""
		(layer "B.Cu")
		(at 295.17467 -293.99992 90)
		(property "Reference" "C1641"
			(at 0 0 90)
			(layer "B.SilkS")
			(hide yes)
			(effects
				(font
					(size 1.27 1.27)
				)
				(justify mirror)
			)
		)
		(property "Value" ""
			(at 0 0 90)
			(layer "B.Fab")
			(effects
				(font
					(size 1.27 1.27)
				)
				(justify mirror)
			)
		)
		(duplicate_pad_numbers_are_jumpers no)
		(fp_line
			(start 0.299974 -0.150114)
			(end -0.299974 -0.150114)
			(stroke
				(width 0.1)
				(type default)
			)
			(layer "B.Fab")
		)
		(fp_line
			(start -0.299974 -0.150114)
			(end -0.299974 0.150114)
			(stroke
				(width 0.1)
				(type default)
			)
			(layer "B.Fab")
		)
		(fp_line
			(start 0.299974 0.150114)
			(end 0.299974 -0.150114)
			(stroke
				(width 0.1)
				(type default)
			)
			(layer "B.Fab")
		)
		(fp_line
			(start -0.299974 0.150114)
			(end 0.299974 0.150114)
			(stroke
				(width 0.1)
				(type default)
			)
			(layer "B.Fab")
		)
		(pad "1" smd rect
			(at 0.2667 0 270)
			(size 0.3048 0.381)
			(layers "B.Cu" "B.Mask" "B.Paste")
			(net "P0V8_PEX2")
		)
		(pad "2" smd rect
			(at -0.2667 0 270)
			(size 0.3048 0.381)
			(layers "B.Cu" "B.Mask" "B.Paste")
			(net "GND")
		)
	)
	(footprint ""
		(layer "B.Cu")
		(at 333.912972 -325.909178 -90)
		(property "Reference" "C4328"
			(at 0 0 90)
			(layer "B.SilkS")
			(hide yes)
			(effects
				(font
					(size 1.27 1.27)
				)
				(justify mirror)
			)
		)
		(property "Value" ""
			(at 0 0 90)
			(layer "B.Fab")
			(effects
				(font
					(size 1.27 1.27)
				)
				(justify mirror)
			)
		)
		(duplicate_pad_numbers_are_jumpers no)
		(fp_line
			(start -1.2954 0.5842)
			(end 1.2954 0.5842)
			(stroke
				(width 0.1524)
				(type default)
			)
			(layer "B.SilkS")
		)
		(fp_line
			(start 1.2954 0.5842)
			(end 1.2954 -0.5842)
			(stroke
				(width 0.1524)
				(type default)
			)
			(layer "B.SilkS")
		)
		(fp_line
			(start -1.2954 -0.5842)
			(end -1.2954 0.5842)
			(stroke
				(width 0.1524)
				(type default)
			)
			(layer "B.SilkS")
		)
		(fp_line
			(start 1.2954 -0.5842)
			(end -1.2954 -0.5842)
			(stroke
				(width 0.1524)
				(type default)
			)
			(layer "B.SilkS")
		)
		(fp_line
			(start -0.8636 0.4572)
			(end 0.8636 0.4572)
			(stroke
				(width 0.1)
				(type default)
			)
			(layer "B.Fab")
		)
		(fp_line
			(start 0.8636 0.4572)
			(end 0.8636 0.4064)
			(stroke
				(width 0.1)
				(type default)
			)
			(layer "B.Fab")
		)
		(fp_line
			(start -1.1938 0.4064)
			(end -0.8636 0.4064)
			(stroke
				(width 0.1)
				(type default)
			)
			(layer "B.Fab")
		)
		(fp_line
			(start -0.8636 0.4064)
			(end -0.8636 0.4572)
			(stroke
				(width 0.1)
				(type default)
			)
			(layer "B.Fab")
		)
		(fp_line
			(start 0.8636 0.4064)
			(end 1.1938 0.4064)
			(stroke
				(width 0.1)
				(type default)
			)
			(layer "B.Fab")
		)
		(fp_line
			(start 1.1938 0.4064)
			(end 1.1938 -0.4064)
			(stroke
				(width 0.1)
				(type default)
			)
			(layer "B.Fab")
		)
		(fp_line
			(start -1.1938 -0.4064)
			(end -1.1938 0.4064)
			(stroke
				(width 0.1)
				(type default)
			)
			(layer "B.Fab")
		)
		(fp_line
			(start -0.8636 -0.4064)
			(end -1.1938 -0.4064)
			(stroke
				(width 0.1)
				(type default)
			)
			(layer "B.Fab")
		)
		(fp_line
			(start 0.8636 -0.4064)
			(end 0.8636 -0.4572)
			(stroke
				(width 0.1)
				(type default)
			)
			(layer "B.Fab")
		)
		(fp_line
			(start 1.1938 -0.4064)
			(end 0.8636 -0.4064)
			(stroke
				(width 0.1)
				(type default)
			)
			(layer "B.Fab")
		)
		(fp_line
			(start -0.8636 -0.4572)
			(end -0.8636 -0.4064)
			(stroke
				(width 0.1)
				(type default)
			)
			(layer "B.Fab")
		)
		(fp_line
			(start 0.8636 -0.4572)
			(end -0.8636 -0.4572)
			(stroke
				(width 0.1)
				(type default)
			)
			(layer "B.Fab")
		)
		(pad "1" smd rect
			(at 0.7366 0 180)
			(size 0.7112 0.8128)
			(layers "B.Cu" "B.Mask" "B.Paste")
			(net "P0V8_SERDES_VDDA_PEX2_C10")
		)
		(pad "2" smd rect
			(at -0.7366 0 180)
			(size 0.7112 0.8128)
			(layers "B.Cu" "B.Mask" "B.Paste")
			(net "GND")
		)
	)
	(footprint ""
		(layer "B.Cu")
		(at 350.65716 -316.003686)
		(property "Reference" "C4379"
			(at 0 0 0)
			(layer "B.SilkS")
			(hide yes)
			(effects
				(font
					(size 1.27 1.27)
				)
				(justify mirror)
			)
		)
		(property "Value" ""
			(at 0 0 0)
			(layer "B.Fab")
			(effects
				(font
					(size 1.27 1.27)
				)
				(justify mirror)
			)
		)
		(duplicate_pad_numbers_are_jumpers no)
		(fp_line
			(start -0.299974 -0.150114)
			(end -0.299974 0.150114)
			(stroke
				(width 0.1)
				(type default)
			)
			(layer "B.Fab")
		)
		(fp_line
			(start -0.299974 0.150114)
			(end 0.299974 0.150114)
			(stroke
				(width 0.1)
				(type default)
			)
			(layer "B.Fab")
		)
		(fp_line
			(start 0.299974 -0.150114)
			(end -0.299974 -0.150114)
			(stroke
				(width 0.1)
				(type default)
			)
			(layer "B.Fab")
		)
		(fp_line
			(start 0.299974 0.150114)
			(end 0.299974 -0.150114)
			(stroke
				(width 0.1)
				(type default)
			)
			(layer "B.Fab")
		)
		(pad "1" smd rect
			(at 0.2667 0 180)
			(size 0.3048 0.381)
			(layers "B.Cu" "B.Mask" "B.Paste")
			(net "P0V8_SERDES_VDDA_PEX3")
		)
		(pad "2" smd rect
			(at -0.2667 0 180)
			(size 0.3048 0.381)
			(layers "B.Cu" "B.Mask" "B.Paste")
			(net "GND")
		)
	)
	(footprint ""
		(layer "B.Cu")
		(at 168.625012 -293.99992 90)
		(property "Reference" "C1378"
			(at 0 0 90)
			(layer "B.SilkS")
			(hide yes)
			(effects
				(font
					(size 1.27 1.27)
				)
				(justify mirror)
			)
		)
		(property "Value" ""
			(at 0 0 90)
			(layer "B.Fab")
			(effects
				(font
					(size 1.27 1.27)
				)
				(justify mirror)
			)
		)
		(duplicate_pad_numbers_are_jumpers no)
		(fp_line
			(start 0.299974 -0.150114)
			(end -0.299974 -0.150114)
			(stroke
				(width 0.1)
				(type default)
			)
			(layer "B.Fab")
		)
		(fp_line
			(start -0.299974 -0.150114)
			(end -0.299974 0.150114)
			(stroke
				(width 0.1)
				(type default)
			)
			(layer "B.Fab")
		)
		(fp_line
			(start 0.299974 0.150114)
			(end 0.299974 -0.150114)
			(stroke
				(width 0.1)
				(type default)
			)
			(layer "B.Fab")
		)
		(fp_line
			(start -0.299974 0.150114)
			(end 0.299974 0.150114)
			(stroke
				(width 0.1)
				(type default)
			)
			(layer "B.Fab")
		)
		(pad "1" smd rect
			(at 0.2667 0 270)
			(size 0.3048 0.381)
			(layers "B.Cu" "B.Mask" "B.Paste")
			(net "P0V8_PEX1")
		)
		(pad "2" smd rect
			(at -0.2667 0 270)
			(size 0.3048 0.381)
			(layers "B.Cu" "B.Mask" "B.Paste")
			(net "GND")
		)
	)
)
